(kicad_pcb
	(version 20221018)
	(generator pcbnew)
	(general
    (thickness 0.908)
  )
	(paper "A4")
	(title_block
    (title "HDMI-MIPI Bridge")
    (date "2024-04-24")
    (rev "1.3.2")
		(comment 9 "footprints 52-55 of 121")
	)
	(layers
    (0 "F.Cu" signal)
    (1 "In1.Cu" signal)
    (2 "In2.Cu" signal)
    (31 "B.Cu" signal)
    (32 "B.Adhes" user "B.Adhesive")
    (33 "F.Adhes" user "F.Adhesive")
    (34 "B.Paste" user)
    (35 "F.Paste" user)
    (36 "B.SilkS" user "B.Silkscreen")
    (37 "F.SilkS" user "F.Silkscreen")
    (38 "B.Mask" user)
    (39 "F.Mask" user)
    (40 "Dwgs.User" user "User.Drawings")
    (41 "Cmts.User" user "User.Comments")
    (42 "Eco1.User" user "User.Eco1")
    (43 "Eco2.User" user "User.Eco2")
    (44 "Edge.Cuts" user)
    (45 "Margin" user)
    (46 "B.CrtYd" user "B.Courtyard")
    (47 "F.CrtYd" user "F.Courtyard")
    (48 "B.Fab" user)
    (49 "F.Fab" user)
  )
	(footprint "antmicro-footprints:Conn_FFC_WE_68715014x22" (layer "F.Cu")
    (at 149.006 132.275)
    (property "Author" "Antmicro")
    (property "License" "Apache-2.0")
    (property "MPN" "68715014022")
    (property "Manufacturer" "Würth Elektronik")
    (property "Sheetfile" "csi.kicad_sch")
    (property "Sheetname" "CSI")
    (property "ki_description" "FFC connector")
    (property "ki_keywords" "CONNECTOR")
    (attr smd)
    (fp_text reference "J6" (at 0 -3.4) (layer "F.SilkS")
        (effects (font (size 0.7 0.7) (thickness 0.15)) (justify left bottom))
    )
    (fp_text value "Conn_FFC_WE_68715014022" (at 0 4.5) (layer "F.Fab")
        (effects (font (size 0.7 0.7) (thickness 0.15)) (justify left bottom))
    )
    (fp_text user "License: Apache-2.0" (at -16.2 7.9) (layer "F.Fab") hide
        (effects (font (size 0.7 0.7) (thickness 0.15)) (justify left bottom))
    )
    (fp_text user "${REFERENCE}" (at -16.2 5.9) (layer "F.Fab") hide
        (effects (font (size 0.7 0.7) (thickness 0.15)) (justify left bottom))
    )
    (fp_text user "Author: Antmicro" (at -16.2 6.9) (layer "F.Fab") hide
        (effects (font (size 0.7 0.7) (thickness 0.15)) (justify left bottom))
    )
    (fp_line (start -15.85 -2.15) (end -12.5 -2.15)
      (stroke (width 0.15) (type solid)) (layer "F.SilkS"))
    (fp_line (start -15.85 2.7) (end -15.85 -2.15)
      (stroke (width 0.15) (type solid)) (layer "F.SilkS"))
    (fp_line (start -12.5 -2.976) (end 12.499 -2.976)
      (stroke (width 0.15) (type solid)) (layer "F.SilkS"))
    (fp_line (start -12.5 -2.15) (end -12.5 -2.976)
      (stroke (width 0.15) (type solid)) (layer "F.SilkS"))
    (fp_line (start 12.499 -2.15) (end 12.499 -2.976)
      (stroke (width 0.15) (type solid)) (layer "F.SilkS"))
    (fp_line (start 15.85 -2.15) (end 12.499 -2.15)
      (stroke (width 0.15) (type solid)) (layer "F.SilkS"))
    (fp_line (start 15.85 2.7) (end -15.85 2.7)
      (stroke (width 0.15) (type solid)) (layer "F.SilkS"))
    (fp_line (start 15.85 2.7) (end 15.85 -2.15)
      (stroke (width 0.15) (type solid)) (layer "F.SilkS"))
    (fp_circle (center -12.9 -2.9) (end -12.85 -2.85)
      (stroke (width 0.15) (type solid)) (fill solid) (layer "F.SilkS"))
    (fp_rect (start -16.2 -3.25) (end 16.2 3.55)
      (stroke (width 0.05) (type solid)) (fill none) (layer "F.CrtYd"))
    (pad "1" smd roundrect (at -12.25 -2.15) (size 0.3 1.2) (layers "F.Cu" "F.Paste" "F.Mask") (roundrect_rratio 0.25)
      (net 14 "+5V") (pintype "passive"))
    (pad "2" smd roundrect (at -11.75 -2.15) (size 0.3 1.2) (layers "F.Cu" "F.Paste" "F.Mask") (roundrect_rratio 0.25)
      (net 14 "+5V") (pintype "passive"))
    (pad "3" smd roundrect (at -11.25 -2.15) (size 0.3 1.2) (layers "F.Cu" "F.Paste" "F.Mask") (roundrect_rratio 0.25)
      (net 9 "+3V3") (pintype "passive"))
    (pad "4" smd roundrect (at -10.75 -2.15) (size 0.3 1.2) (layers "F.Cu" "F.Paste" "F.Mask") (roundrect_rratio 0.25)
      (net 9 "+3V3") (pintype "passive"))
    (pad "5" smd roundrect (at -10.25 -2.15) (size 0.3 1.2) (layers "F.Cu" "F.Paste" "F.Mask") (roundrect_rratio 0.25)
      (net 73 "/CSI/SPI_CS") (pintype "passive+no_connect"))
    (pad "6" smd roundrect (at -9.75 -2.15) (size 0.3 1.2) (layers "F.Cu" "F.Paste" "F.Mask") (roundrect_rratio 0.25)
      (net 72 "/CSI/SPI_MOSI") (pintype "passive+no_connect"))
    (pad "7" smd roundrect (at -9.25 -2.15) (size 0.3 1.2) (layers "F.Cu" "F.Paste" "F.Mask") (roundrect_rratio 0.25)
      (net 71 "/CSI/SPI_MISO") (pintype "passive+no_connect"))
    (pad "8" smd roundrect (at -8.75 -2.15) (size 0.3 1.2) (layers "F.Cu" "F.Paste" "F.Mask") (roundrect_rratio 0.25)
      (net 70 "/CSI/SPI_SCK") (pintype "passive+no_connect"))
    (pad "9" smd roundrect (at -8.25 -2.15) (size 0.3 1.2) (layers "F.Cu" "F.Paste" "F.Mask") (roundrect_rratio 0.25)
      (net 69 "I2C1_SCL") (pintype "passive"))
    (pad "10" smd roundrect (at -7.75 -2.15) (size 0.3 1.2) (layers "F.Cu" "F.Paste" "F.Mask") (roundrect_rratio 0.25)
      (net 68 "I2C1_SDA") (pintype "passive"))
    (pad "11" smd roundrect (at -7.25 -2.15) (size 0.3 1.2) (layers "F.Cu" "F.Paste" "F.Mask") (roundrect_rratio 0.25)
      (net 67 "I2C3_SCL") (pintype "passive"))
    (pad "12" smd roundrect (at -6.75 -2.15) (size 0.3 1.2) (layers "F.Cu" "F.Paste" "F.Mask") (roundrect_rratio 0.25)
      (net 66 "I2C3_SDA") (pintype "passive"))
    (pad "13" smd roundrect (at -6.25 -2.15) (size 0.3 1.2) (layers "F.Cu" "F.Paste" "F.Mask") (roundrect_rratio 0.25)
      (net 65 "/CSI/UART4_RX") (pintype "passive+no_connect"))
    (pad "14" smd roundrect (at -5.75 -2.15) (size 0.3 1.2) (layers "F.Cu" "F.Paste" "F.Mask") (roundrect_rratio 0.25)
      (net 64 "/CSI/UART4_TX") (pintype "passive+no_connect"))
    (pad "15" smd roundrect (at -5.25 -2.15) (size 0.3 1.2) (layers "F.Cu" "F.Paste" "F.Mask") (roundrect_rratio 0.25)
      (net 63 "/CSI/UART3_RX") (pintype "passive+no_connect"))
    (pad "16" smd roundrect (at -4.75 -2.15) (size 0.3 1.2) (layers "F.Cu" "F.Paste" "F.Mask") (roundrect_rratio 0.25)
      (net 62 "/CSI/UART3_TX") (pintype "passive+no_connect"))
    (pad "17" smd roundrect (at -4.25 -2.15) (size 0.3 1.2) (layers "F.Cu" "F.Paste" "F.Mask") (roundrect_rratio 0.25)
      (net 61 "/CSI/GPIO4") (pintype "passive+no_connect"))
    (pad "18" smd roundrect (at -3.75 -2.15) (size 0.3 1.2) (layers "F.Cu" "F.Paste" "F.Mask") (roundrect_rratio 0.25)
      (net 60 "/CSI/GPIO3") (pintype "passive+no_connect"))
    (pad "19" smd roundrect (at -3.25 -2.15) (size 0.3 1.2) (layers "F.Cu" "F.Paste" "F.Mask") (roundrect_rratio 0.25)
      (net 59 "/CSI/GPIO2") (pintype "passive+no_connect"))
    (pad "20" smd roundrect (at -2.75 -2.15) (size 0.3 1.2) (layers "F.Cu" "F.Paste" "F.Mask") (roundrect_rratio 0.25)
      (net 58 "/CSI/GPIO1") (pintype "passive+no_connect"))
    (pad "21" smd roundrect (at -2.25 -2.15) (size 0.3 1.2) (layers "F.Cu" "F.Paste" "F.Mask") (roundrect_rratio 0.25)
      (net 144 "unconnected-(J6-Pad21)") (pintype "passive+no_connect"))
    (pad "22" smd roundrect (at -1.75 -2.15) (size 0.3 1.2) (layers "F.Cu" "F.Paste" "F.Mask") (roundrect_rratio 0.25)
      (net 57 "CSI1_CLK_P") (pintype "passive"))
    (pad "23" smd roundrect (at -1.25 -2.15) (size 0.3 1.2) (layers "F.Cu" "F.Paste" "F.Mask") (roundrect_rratio 0.25)
      (net 56 "CSI1_CLK_N") (pintype "passive"))
    (pad "24" smd roundrect (at -0.75 -2.15) (size 0.3 1.2) (layers "F.Cu" "F.Paste" "F.Mask") (roundrect_rratio 0.25)
      (net 145 "unconnected-(J6-Pad24)") (pintype "passive+no_connect"))
    (pad "25" smd roundrect (at -0.25 -2.15) (size 0.3 1.2) (layers "F.Cu" "F.Paste" "F.Mask") (roundrect_rratio 0.25)
      (net 55 "CSI1_D1_P") (pintype "passive"))
    (pad "26" smd roundrect (at 0.248 -2.15) (size 0.3 1.2) (layers "F.Cu" "F.Paste" "F.Mask") (roundrect_rratio 0.25)
      (net 54 "CSI1_D1_N") (pintype "passive"))
    (pad "27" smd roundrect (at 0.748 -2.15) (size 0.3 1.2) (layers "F.Cu" "F.Paste" "F.Mask") (roundrect_rratio 0.25)
      (net 53 "CSI1_D2_P") (pintype "passive"))
    (pad "28" smd roundrect (at 1.249 -2.15) (size 0.3 1.2) (layers "F.Cu" "F.Paste" "F.Mask") (roundrect_rratio 0.25)
      (net 52 "CSI1_D2_N") (pintype "passive"))
    (pad "29" smd roundrect (at 1.749 -2.15) (size 0.3 1.2) (layers "F.Cu" "F.Paste" "F.Mask") (roundrect_rratio 0.25)
      (net 51 "CSI1_D3_P") (pintype "passive"))
    (pad "30" smd roundrect (at 2.249 -2.15) (size 0.3 1.2) (layers "F.Cu" "F.Paste" "F.Mask") (roundrect_rratio 0.25)
      (net 50 "CSI1_D3_N") (pintype "passive"))
    (pad "31" smd roundrect (at 2.749 -2.15) (size 0.3 1.2) (layers "F.Cu" "F.Paste" "F.Mask") (roundrect_rratio 0.25)
      (net 49 "CSI1_D4_P") (pintype "passive"))
    (pad "32" smd roundrect (at 3.249 -2.15) (size 0.3 1.2) (layers "F.Cu" "F.Paste" "F.Mask") (roundrect_rratio 0.25)
      (net 48 "CSI1_D4_N") (pintype "passive"))
    (pad "33" smd roundrect (at 3.749 -2.15) (size 0.3 1.2) (layers "F.Cu" "F.Paste" "F.Mask") (roundrect_rratio 0.25)
      (net 2 "GND") (pintype "passive"))
    (pad "34" smd roundrect (at 4.248 -2.15) (size 0.3 1.2) (layers "F.Cu" "F.Paste" "F.Mask") (roundrect_rratio 0.25)
      (net 47 "/CSI/CSI2_D1_P") (pintype "passive+no_connect"))
    (pad "35" smd roundrect (at 4.748 -2.15) (size 0.3 1.2) (layers "F.Cu" "F.Paste" "F.Mask") (roundrect_rratio 0.25)
      (net 46 "/CSI/CSI2_D1_N") (pintype "passive+no_connect"))
    (pad "36" smd roundrect (at 5.248 -2.15) (size 0.3 1.2) (layers "F.Cu" "F.Paste" "F.Mask") (roundrect_rratio 0.25)
      (net 2 "GND") (pintype "passive"))
    (pad "37" smd roundrect (at 5.749 -2.15) (size 0.3 1.2) (layers "F.Cu" "F.Paste" "F.Mask") (roundrect_rratio 0.25)
      (net 45 "/CSI/CSI2_CLK_P") (pintype "passive+no_connect"))
    (pad "38" smd roundrect (at 6.249 -2.15) (size 0.3 1.2) (layers "F.Cu" "F.Paste" "F.Mask") (roundrect_rratio 0.25)
      (net 44 "/CSI/CSI2_CLK_N") (pintype "passive+no_connect"))
    (pad "39" smd roundrect (at 6.749 -2.15) (size 0.3 1.2) (layers "F.Cu" "F.Paste" "F.Mask") (roundrect_rratio 0.25)
      (net 2 "GND") (pintype "passive"))
    (pad "40" smd roundrect (at 7.249 -2.15) (size 0.3 1.2) (layers "F.Cu" "F.Paste" "F.Mask") (roundrect_rratio 0.25)
      (net 43 "CSI3_CLK_P") (pintype "passive"))
    (pad "41" smd roundrect (at 7.749 -2.15) (size 0.3 1.2) (layers "F.Cu" "F.Paste" "F.Mask") (roundrect_rratio 0.25)
      (net 42 "CSI3_CLK_N") (pintype "passive"))
    (pad "42" smd roundrect (at 8.249 -2.15) (size 0.3 1.2) (layers "F.Cu" "F.Paste" "F.Mask") (roundrect_rratio 0.25)
      (net 2 "GND") (pintype "passive"))
    (pad "43" smd roundrect (at 8.749 -2.15) (size 0.3 1.2) (layers "F.Cu" "F.Paste" "F.Mask") (roundrect_rratio 0.25)
      (net 41 "CSI3_D1_P") (pintype "passive"))
    (pad "44" smd roundrect (at 9.249 -2.15) (size 0.3 1.2) (layers "F.Cu" "F.Paste" "F.Mask") (roundrect_rratio 0.25)
      (net 40 "CSI3_D1_N") (pintype "passive"))
    (pad "45" smd roundrect (at 9.749 -2.15) (size 0.3 1.2) (layers "F.Cu" "F.Paste" "F.Mask") (roundrect_rratio 0.25)
      (net 39 "CSI3_D2_P") (pintype "passive"))
    (pad "46" smd roundrect (at 10.249 -2.15) (size 0.3 1.2) (layers "F.Cu" "F.Paste" "F.Mask") (roundrect_rratio 0.25)
      (net 38 "CSI3_D2_N") (pintype "passive"))
    (pad "47" smd roundrect (at 10.749 -2.15) (size 0.3 1.2) (layers "F.Cu" "F.Paste" "F.Mask") (roundrect_rratio 0.25)
      (net 37 "CSI3_D3_P") (pintype "passive"))
    (pad "48" smd roundrect (at 11.249 -2.15) (size 0.3 1.2) (layers "F.Cu" "F.Paste" "F.Mask") (roundrect_rratio 0.25)
      (net 36 "CSI3_D3_N") (pintype "passive"))
    (pad "49" smd roundrect (at 11.749 -2.15) (size 0.3 1.2) (layers "F.Cu" "F.Paste" "F.Mask") (roundrect_rratio 0.25)
      (net 35 "CSI3_D4_P") (pintype "passive"))
    (pad "50" smd roundrect (at 12.249 -2.15) (size 0.3 1.2) (layers "F.Cu" "F.Paste" "F.Mask") (roundrect_rratio 0.25)
      (net 34 "CSI3_D4_N") (pintype "passive"))
    (pad "MP1" smd roundrect (at -14.198 -0.3) (size 2.7 3) (layers "F.Cu" "F.Paste" "F.Mask") (roundrect_rratio 0.05)
      (net 2 "GND") (pinfunction "MP") (pintype "passive"))
    (pad "MP2" smd roundrect (at 14.198 -0.3) (size 2.7 3) (layers "F.Cu" "F.Paste" "F.Mask") (roundrect_rratio 0.05)
      (net 2 "GND") (pinfunction "MP") (pintype "passive"))
  )
	(footprint "antmicro-footprints:FB_0603_1608Metric" (layer "F.Cu")
    (at 170.2 99.85 90)
    (property "Author" "Antmicro")
    (property "Current" "")
    (property "License" "Apache-2.0")
    (property "MPN" "BLM18SG121TN1D")
    (property "Manufacturer" "Murata")
    (property "Public" "False")
    (property "Sheetfile" "channel2.kicad_sch")
    (property "Sheetname" "Channel 2")
    (property "Val" "120Z/3A")
    (property "ki_description" "Ferrite Bead, 0603 [1608 Metric], 120 ohm, 3 A, BLM18S, 0.025 ohm, ± 25%, DC power line (thin type) ")
    (property "ki_keywords" "0603, SMT, FERRITE BEAD, PASSIVE")
    (attr smd)
    (fp_text reference "FB7" (at -0.94 1.58 90) (layer "F.SilkS")
        (effects (font (size 0.65 0.65) (thickness 0.13)) (justify left bottom))
    )
    (fp_text value "FB_120Z_3A_Murata-BLM18SG_0603" (at 0 1.5 90) (layer "F.Fab")
        (effects (font (size 0.65 0.65) (thickness 0.13)) (justify left bottom))
    )
    (fp_text user "License: Apache-2.0" (at -1.653 5.9 90) (layer "F.Fab") hide
        (effects (font (size 0.7 0.7) (thickness 0.15)) (justify left bottom))
    )
    (fp_text user "${REFERENCE}" (at -1.653 4.6 90) (layer "F.Fab") hide
        (effects (font (size 0.7 0.7) (thickness 0.15)) (justify left bottom))
    )
    (fp_text user "Author: Antmicro" (at -1.653 3.162 90) (layer "F.Fab") hide
        (effects (font (size 0.7 0.7) (thickness 0.15)) (justify left bottom))
    )
    (fp_line (start -0.15 -0.4) (end 0.15 -0.4)
      (stroke (width 0.15) (type solid)) (layer "F.SilkS"))
    (fp_line (start -0.15 0.4) (end 0.15 0.4)
      (stroke (width 0.15) (type solid)) (layer "F.SilkS"))
    (fp_rect (start -1.25 -0.65) (end 1.25 0.65)
      (stroke (width 0.05) (type solid)) (fill none) (layer "F.CrtYd"))
    (fp_line (start -0.803 0.406) (end -0.803 -0.408)
      (stroke (width 0.15) (type solid)) (layer "F.Fab"))
    (fp_line (start 0.8 -0.408) (end -0.803 -0.408)
      (stroke (width 0.15) (type solid)) (layer "F.Fab"))
    (fp_line (start 0.8 -0.408) (end 0.8 0.406)
      (stroke (width 0.15) (type solid)) (layer "F.Fab"))
    (fp_line (start 0.8 0.406) (end -0.803 0.406)
      (stroke (width 0.15) (type solid)) (layer "F.Fab"))
    (pad "1" smd roundrect (at -0.7 0 90) (size 0.8 1) (layers "F.Cu" "F.Paste" "F.Mask") (roundrect_rratio 0.2)
      (net 2 "GND") (pintype "passive"))
    (pad "2" smd roundrect (at 0.7 0 90) (size 0.8 1) (layers "F.Cu" "F.Paste" "F.Mask") (roundrect_rratio 0.2)
      (net 29 "Net-(FB7-Pad2)") (pintype "passive"))
  )
	(footprint "antmicro-footprints:C_0603_1608Metric" (layer "F.Cu")
    (at 140.2 113 180)
    (descr "Capacitor SMD 0603")
    (tags "capacitor 0603")
    (property "Author" "Antmicro")
    (property "Dielectric" "")
    (property "License" "Apache-2.0")
    (property "MPN" "C1608X5R1V475M080AC")
    (property "Manufacturer" "TDK")
    (property "Public" "False")
    (property "Sheetfile" "channel1.kicad_sch")
    (property "Sheetname" "Channel 1")
    (property "Val" "4u7")
    (property "Voltage" "")
    (property "ki_description" "SMD Multilayer Ceramic Capacitor, 4.7 µF, 35 V, 0603 [1608 Metric], ± 20%, X5R, C")
    (property "ki_keywords" "0603, SMT, CAPACITOR, PASSIVE, CERAMIC, MLCC")
    (attr smd)
    (fp_text reference "C10" (at 1.9 -5.6) (layer "F.SilkS")
        (effects (font (size 0.65 0.65) (thickness 0.13)) (justify right bottom))
    )
    (fp_text value "C_4u7_0603" (at 0 1.6) (layer "F.Fab")
        (effects (font (size 0.65 0.65) (thickness 0.13)) (justify right bottom))
    )
    (fp_text user "License: Apache-2.0" (at -1.682 5.895) (layer "F.Fab") hide
        (effects (font (size 0.7 0.7) (thickness 0.15)) (justify right bottom))
    )
    (fp_text user "Author: Antmicro" (at -1.682 4.894) (layer "F.Fab") hide
        (effects (font (size 0.7 0.7) (thickness 0.15)) (justify right bottom))
    )
    (fp_text user "${REFERENCE}" (at -1.682 3.895) (layer "F.Fab") hide
        (effects (font (size 0.7 0.7) (thickness 0.15)) (justify right bottom))
    )
    (fp_line (start -0.15 -0.4) (end 0.15 -0.4)
      (stroke (width 0.15) (type solid)) (layer "F.SilkS"))
    (fp_line (start -0.15 0.4) (end 0.15 0.4)
      (stroke (width 0.15) (type solid)) (layer "F.SilkS"))
    (fp_rect (start -1.25 -0.65) (end 1.25 0.65)
      (stroke (width 0.05) (type solid)) (fill none) (layer "F.CrtYd"))
    (fp_rect (start -0.8 -0.4) (end 0.8 0.4)
      (stroke (width 0.15) (type solid)) (fill none) (layer "F.Fab"))
    (pad "1" smd roundrect (at -0.7 0 180) (size 0.8 1) (layers "F.Cu" "F.Paste" "F.Mask") (roundrect_rratio 0.2)
      (net 2 "GND") (pintype "passive"))
    (pad "2" smd roundrect (at 0.7 0 180) (size 0.8 1) (layers "F.Cu" "F.Paste" "F.Mask") (roundrect_rratio 0.2)
      (net 7 "Net-(C10-Pad2)") (pintype "passive"))
  )
	(footprint "antmicro-footprints:C_0402_1005Metric" (layer "F.Cu")
    (at 167.91 106.07)
    (descr "Capacitor SMD 0402")
    (tags "capacitor SMD 0402")
    (property "Author" "Antmicro")
    (property "Dielectric" "X5R")
    (property "License" "Apache-2.0")
    (property "MPN" "GRM155R61H104KE14D")
    (property "Manufacturer" "Murata")
    (property "Public" "False")
    (property "Sheetfile" "channel2.kicad_sch")
    (property "Sheetname" "Channel 2")
    (property "Val" "100n")
    (property "Voltage" "50V")
    (property "ki_description" "SMD Multilayer Ceramic Capacitor, 0.1 µF, 50 V, 0402 [1005 Metric], ± 10%, X5R, GRM Series")
    (property "ki_keywords" "0402, SMT, CAPACITOR, PASSIVE, CERAMIC, MLCC")
    (attr smd)
    (fp_text reference "C37" (at 0.88 0.38) (layer "F.SilkS")
        (effects (font (size 0.65 0.65) (thickness 0.13)) (justify left bottom))
    )
    (fp_text value "C_100n_0402" (at 0 1.4) (layer "F.Fab")
        (effects (font (size 0.65 0.65) (thickness 0.13)) (justify left bottom))
    )
    (fp_text user "Author: Antmicro" (at -0.932 4.17) (layer "F.Fab") hide
        (effects (font (size 0.7 0.7) (thickness 0.15)) (justify left bottom))
    )
    (fp_text user "License: Apache-2.0" (at -0.932 5.17) (layer "F.Fab") hide
        (effects (font (size 0.7 0.7) (thickness 0.15)) (justify left bottom))
    )
    (fp_text user "${REFERENCE}" (at -0.932 3.168) (layer "F.Fab") hide
        (effects (font (size 0.7 0.7) (thickness 0.15)) (justify left bottom))
    )
    (fp_rect (start -0.925 -0.47) (end 0.925 0.47)
      (stroke (width 0.05) (type default)) (fill none) (layer "F.CrtYd"))
    (fp_line (start -0.494 -0.25) (end 0.504 -0.25)
      (stroke (width 0.15) (type solid)) (layer "F.Fab"))
    (fp_line (start -0.494 0.248) (end -0.494 -0.25)
      (stroke (width 0.15) (type solid)) (layer "F.Fab"))
    (fp_line (start 0.504 -0.25) (end 0.504 0.248)
      (stroke (width 0.15) (type solid)) (layer "F.Fab"))
    (fp_line (start 0.504 0.248) (end -0.494 0.248)
      (stroke (width 0.15) (type solid)) (layer "F.Fab"))
    (pad "1" smd roundrect (at -0.48 0) (size 0.59 0.64) (layers "F.Cu" "F.Paste" "F.Mask") (roundrect_rratio 0.25)
      (net 9 "+3V3") (pintype "passive"))
    (pad "2" smd roundrect (at 0.48 0) (size 0.59 0.64) (layers "F.Cu" "F.Paste" "F.Mask") (roundrect_rratio 0.25)
      (net 2 "GND") (pintype "passive"))
  )
)
